# T6G (Grand Teton) — schematic netlist excerpt (pin names and nets, part order shuffled) for the footprints in the layout excerpt that follows; sources: Cadence DE-HDL packaged netlist, KiCad conversion of 04192023_DAF0TMB3IC0_F0TG_MB_C_brd_V02_OCP.brd

R2317  Q_RES  10K 1% CHIP  pkg 0402LF  page 145 : A = P3V3_E1S_0 ; B = PU_E1S_0_DUALPORT_EN_N
C1577  Q_CAP_DIFFBUS  DIFF BUS_0.22UF 6.3V 20% X6S  pkg C0201  page 65 : \1\ = P5E_CPU0_G3_TX_C_DP<1> ; \2\ = P5E_CPU0_G3_TX_DP<1>
PR420  Q_RES  5.6 1% CHIP  pkg 0402LF  page 203 : A = SW_PVDDCR_CPU1_P0_BOOT6 ; B = SW_PVDDCR_CPU1_P0_BOOT6_R

(kicad_pcb
	(version 20260206)
	(generator "pcbnew")
	(generator_version "10.0")
	(general
		(thickness 1.6)
		(legacy_teardrops no)
	)
	(paper "A4")
	(title_block
		(title "04192023_DAF0TMB3IC0_F0TG_MB_C_brd_V02_OCP.brd")
		(comment 1 "Grand Teton / footprints 3360-3362 of 8354")
	)
	(layers
		(0 "F.Cu" signal "TOP")
		(4 "In1.Cu" signal "GND")
		(6 "In2.Cu" signal "IN1")
		(8 "In3.Cu" signal "GND1")
		(10 "In4.Cu" signal "IN2")
		(12 "In5.Cu" signal "GND2")
		(14 "In6.Cu" signal "IN3")
		(16 "In7.Cu" signal "GND3")
		(18 "In8.Cu" signal "VCC")
		(20 "In9.Cu" signal "VCC1")
		(22 "In10.Cu" signal "GND4")
		(24 "In11.Cu" signal "IN4")
		(26 "In12.Cu" signal "GND5")
		(28 "In13.Cu" signal "IN5")
		(30 "In14.Cu" signal "GND6")
		(32 "In15.Cu" signal "IN6")
		(34 "In16.Cu" signal "GND7")
		(2 "B.Cu" signal "BOTTOM")
		(9 "F.Adhes" user "F.Adhesive")
		(11 "B.Adhes" user "B.Adhesive")
		(13 "F.Paste" user "Package Geometry/Pastemask Top")
		(15 "B.Paste" user "Package Geometry/Pastemask Bottom")
		(5 "F.SilkS" user "Ref Des/Silkscreen Top")
		(7 "B.SilkS" user "Ref Des/Silkscreen Bottom")
		(1 "F.Mask" user "Board Geometry/Soldermask Top")
		(3 "B.Mask" user "Board Geometry/Soldermask Bottom")
		(17 "Dwgs.User" user "User.Drawings")
		(19 "Cmts.User" user "User.Comments")
		(21 "Eco1.User" user "User.Eco1")
		(23 "Eco2.User" user "User.Eco2")
		(25 "Edge.Cuts" user "Board Geometry/Outline")
		(27 "Margin" user)
		(31 "F.CrtYd" user "Package Geometry/Place Bound Top")
		(29 "B.CrtYd" user "Package Geometry/Place Bound Bottom")
		(35 "F.Fab" user "Ref Des/Assembly Top")
		(33 "B.Fab" user "Ref Des/Assembly Bottom")
	)
	(footprint ""
		(layer "F.Cu")
		(at 239.50803 -47.003208 180)
		(property "Reference" "R2317"
			(at 0 0 180)
			(layer "F.SilkS")
			(hide yes)
			(effects
				(font
					(size 1.27 1.27)
				)
			)
		)
		(property "Value" ""
			(at 0 0 180)
			(layer "F.Fab")
			(effects
				(font
					(size 1.27 1.27)
				)
			)
		)
		(duplicate_pad_numbers_are_jumpers no)
		(fp_line
			(start 0.7874 0.4064)
			(end -0.7874 0.4064)
			(stroke
				(width 0.1524)
				(type default)
			)
			(layer "F.SilkS")
		)
		(fp_line
			(start 0.7874 -0.4064)
			(end 0.7874 0.4064)
			(stroke
				(width 0.1524)
				(type default)
			)
			(layer "F.SilkS")
		)
		(fp_line
			(start -0.7874 0.4064)
			(end -0.7874 -0.4064)
			(stroke
				(width 0.1524)
				(type default)
			)
			(layer "F.SilkS")
		)
		(fp_line
			(start -0.7874 -0.4064)
			(end 0.7874 -0.4064)
			(stroke
				(width 0.1524)
				(type default)
			)
			(layer "F.SilkS")
		)
		(fp_line
			(start 0.67945 0.3048)
			(end 0.120396 0.3048)
			(stroke
				(width 0.1)
				(type default)
			)
			(layer "F.Fab")
		)
		(fp_line
			(start 0.67945 -0.3048)
			(end 0.67945 0.3048)
			(stroke
				(width 0.1)
				(type default)
			)
			(layer "F.Fab")
		)
		(fp_line
			(start 0.12065 -0.2794)
			(end 0.12065 -0.3048)
			(stroke
				(width 0.1)
				(type default)
			)
			(layer "F.Fab")
		)
		(fp_line
			(start 0.12065 -0.3048)
			(end 0.67945 -0.3048)
			(stroke
				(width 0.1)
				(type default)
			)
			(layer "F.Fab")
		)
		(fp_line
			(start 0.120396 0.3048)
			(end 0.120396 0.2794)
			(stroke
				(width 0.1)
				(type default)
			)
			(layer "F.Fab")
		)
		(fp_line
			(start 0.120396 0.2794)
			(end -0.12065 0.2794)
			(stroke
				(width 0.1)
				(type default)
			)
			(layer "F.Fab")
		)
		(fp_line
			(start -0.12065 0.3048)
			(end -0.67945 0.3048)
			(stroke
				(width 0.1)
				(type default)
			)
			(layer "F.Fab")
		)
		(fp_line
			(start -0.12065 0.2794)
			(end -0.12065 0.3048)
			(stroke
				(width 0.1)
				(type default)
			)
			(layer "F.Fab")
		)
		(fp_line
			(start -0.12065 -0.2794)
			(end 0.12065 -0.2794)
			(stroke
				(width 0.1)
				(type default)
			)
			(layer "F.Fab")
		)
		(fp_line
			(start -0.12065 -0.305054)
			(end -0.12065 -0.2794)
			(stroke
				(width 0.1)
				(type default)
			)
			(layer "F.Fab")
		)
		(fp_line
			(start -0.67945 0.3048)
			(end -0.67945 -0.305054)
			(stroke
				(width 0.1)
				(type default)
			)
			(layer "F.Fab")
		)
		(fp_line
			(start -0.67945 -0.305054)
			(end -0.12065 -0.305054)
			(stroke
				(width 0.1)
				(type default)
			)
			(layer "F.Fab")
		)
		(pad "1" smd circle
			(at -0.40005 0 180)
			(size 0 0)
			(layers "F.Cu" "F.Mask" "F.Paste")
			(net "P3V3_E1S_0")
		)
		(pad "2" smd circle
			(at 0.40005 0 180)
			(size 0 0)
			(layers "F.Cu" "F.Mask" "F.Paste")
			(net "PU_E1S_0_DUALPORT_EN_N")
		)
	)
	(footprint ""
		(layer "F.Cu")
		(at 430.3776 -16.100298 90)
		(property "Reference" "C1577"
			(at 0 0 90)
			(layer "F.SilkS")
			(hide yes)
			(effects
				(font
					(size 1.27 1.27)
				)
			)
		)
		(property "Value" ""
			(at 0 0 90)
			(layer "F.Fab")
			(effects
				(font
					(size 1.27 1.27)
				)
			)
		)
		(duplicate_pad_numbers_are_jumpers no)
		(fp_line
			(start 0.299974 -0.150114)
			(end 0.299974 0.150114)
			(stroke
				(width 0.1)
				(type default)
			)
			(layer "F.Fab")
		)
		(fp_line
			(start -0.299974 -0.150114)
			(end 0.299974 -0.150114)
			(stroke
				(width 0.1)
				(type default)
			)
			(layer "F.Fab")
		)
		(fp_line
			(start 0.299974 0.150114)
			(end -0.299974 0.150114)
			(stroke
				(width 0.1)
				(type default)
			)
			(layer "F.Fab")
		)
		(fp_line
			(start -0.299974 0.150114)
			(end -0.299974 -0.150114)
			(stroke
				(width 0.1)
				(type default)
			)
			(layer "F.Fab")
		)
		(pad "1" smd rect
			(at -0.2667 0 90)
			(size 0.3048 0.381)
			(layers "F.Cu" "F.Mask" "F.Paste")
			(net "P5E_CPU0_G3_TX_C_DP<1>")
		)
		(pad "2" smd rect
			(at 0.2667 0 90)
			(size 0.3048 0.381)
			(layers "F.Cu" "F.Mask" "F.Paste")
			(net "P5E_CPU0_G3_TX_DP<1>")
		)
	)
	(footprint ""
		(layer "F.Cu")
		(at 352.425254 -344.586306 90)
		(property "Reference" "PR420"
			(at 0 0 90)
			(layer "F.SilkS")
			(hide yes)
			(effects
				(font
					(size 1.27 1.27)
				)
			)
		)
		(property "Value" ""
			(at 0 0 90)
			(layer "F.Fab")
			(effects
				(font
					(size 1.27 1.27)
				)
			)
		)
		(duplicate_pad_numbers_are_jumpers no)
		(fp_line
			(start 0.7874 -0.4064)
			(end 0.7874 0.4064)
			(stroke
				(width 0.1524)
				(type default)
			)
			(layer "F.SilkS")
		)
		(fp_line
			(start -0.7874 -0.4064)
			(end 0.7874 -0.4064)
			(stroke
				(width 0.1524)
				(type default)
			)
			(layer "F.SilkS")
		)
		(fp_line
			(start 0.7874 0.4064)
			(end -0.7874 0.4064)
			(stroke
				(width 0.1524)
				(type default)
			)
			(layer "F.SilkS")
		)
		(fp_line
			(start -0.7874 0.4064)
			(end -0.7874 -0.4064)
			(stroke
				(width 0.1524)
				(type default)
			)
			(layer "F.SilkS")
		)
		(fp_line
			(start -0.12065 -0.305054)
			(end -0.12065 -0.2794)
			(stroke
				(width 0.1)
				(type default)
			)
			(layer "F.Fab")
		)
		(fp_line
			(start -0.67945 -0.305054)
			(end -0.12065 -0.305054)
			(stroke
				(width 0.1)
				(type default)
			)
			(layer "F.Fab")
		)
		(fp_line
			(start 0.67945 -0.3048)
			(end 0.67945 0.3048)
			(stroke
				(width 0.1)
				(type default)
			)
			(layer "F.Fab")
		)
		(fp_line
			(start 0.12065 -0.3048)
			(end 0.67945 -0.3048)
			(stroke
				(width 0.1)
				(type default)
			)
			(layer "F.Fab")
		)
		(fp_line
			(start 0.12065 -0.2794)
			(end 0.12065 -0.3048)
			(stroke
				(width 0.1)
				(type default)
			)
			(layer "F.Fab")
		)
		(fp_line
			(start -0.12065 -0.2794)
			(end 0.12065 -0.2794)
			(stroke
				(width 0.1)
				(type default)
			)
			(layer "F.Fab")
		)
		(fp_line
			(start 0.120396 0.2794)
			(end -0.12065 0.2794)
			(stroke
				(width 0.1)
				(type default)
			)
			(layer "F.Fab")
		)
		(fp_line
			(start -0.12065 0.2794)
			(end -0.12065 0.3048)
			(stroke
				(width 0.1)
				(type default)
			)
			(layer "F.Fab")
		)
		(fp_line
			(start 0.67945 0.3048)
			(end 0.120396 0.3048)
			(stroke
				(width 0.1)
				(type default)
			)
			(layer "F.Fab")
		)
		(fp_line
			(start 0.120396 0.3048)
			(end 0.120396 0.2794)
			(stroke
				(width 0.1)
				(type default)
			)
			(layer "F.Fab")
		)
		(fp_line
			(start -0.12065 0.3048)
			(end -0.67945 0.3048)
			(stroke
				(width 0.1)
				(type default)
			)
			(layer "F.Fab")
		)
		(fp_line
			(start -0.67945 0.3048)
			(end -0.67945 -0.305054)
			(stroke
				(width 0.1)
				(type default)
			)
			(layer "F.Fab")
		)
		(pad "1" smd circle
			(at -0.40005 0 90)
			(size 0 0)
			(layers "F.Cu" "F.Mask" "F.Paste")
			(net "SW_PVDDCR_CPU1_P0_BOOT6")
		)
		(pad "2" smd circle
			(at 0.40005 0 90)
			(size 0 0)
			(layers "F.Cu" "F.Mask" "F.Paste")
			(net "SW_PVDDCR_CPU1_P0_BOOT6_R")
		)
	)
)
